FILE_TYPE = MACRO_DRAWING;
SET COLOR_WIRE YELLOW;
SET COLOR_PROP MONO;
SET COLOR_DOT WHITE;
SET COLOR_ARC YELLOW;
SET COLOR_BODY GREEN;
SET COLOR_NOTE MONO;
SET PROP_DISPLAY VALUE;
SET PAGE_NUMBER P180;
FORCEADD INTEL_CORP_BPAGE..1
(4250 200);
FORCEPROP 1 LAST CUSTOM_TXT_CDS <CURRENT_DESIGN_SHEET> OF <TOTAL_DESIGN_SHEETS>
J 0
(3750 225);
PAINT GREEN (3750 225);
FORCEPROP 1 LAST CUSTOM_TXT_CDS <CON_LAST_MODIFIED>
J 0
(2325 550);
PAINT GREEN (2325 550);
FORCEPROP 2 LAST CUSTOM_TXT_CDS <XR_PAGE_TITLE>
J 0
(-3640 5450);
DISPLAY 0.638298 (-3640 5450);
PAINT PINK (-3640 5450);
DISPLAY INVISIBLE (-3640 5450);
FORCEPROP 1 LAST SCH_ADDRESS3 Santa Clara, CA 95052-8119
J 0
(275 225);
DISPLAY 0.617021 (275 225);
PAINT YELLOW (275 225);
FORCEPROP 1 LAST SCH_ADDRESS2 P.O. BOX 58119
J 0
(275 275);
DISPLAY 0.617021 (275 275);
PAINT YELLOW (275 275);
FORCEPROP 1 LAST SCH_ADDRESS1 2200 Mission College Blvd.
J 0
(275 325);
DISPLAY 0.617021 (275 325);
PAINT YELLOW (275 325);
FORCEPROP 1 LAST SCH_TITLE SPARE
J 0
(-3700 250);
DISPLAY 1.212766 (-3700 250);
PAINT YELLOW (-3700 250);
FORCEPROP 1 LAST SCH_NUMBER H4694802
J 0
(2950 350);
DISPLAY 1.212766 (2950 350);
PAINT YELLOW (2950 350);
FORCEPROP 1 LAST SCH_DEPT BESD
J 1
(-200 300);
DISPLAY 1.212766 (-200 300);
PAINT YELLOW (-200 300);
FORCEPROP 1 LAST SCH_REV 2.420
J 0
(4000 350);
DISPLAY 0.978723 (4000 350);
PAINT YELLOW (4000 350);
FORCEPROP 1 LAST COMMENT_BODY TRUE
J 0
(4262 212);
DISPLAY 0.468085 (4262 212);
PAINT PEACH (4262 212);
DISPLAY INVISIBLE (4262 212);
FORCEPROP 2 LAST CDS_LIB mstr_symbols
J 0
(4250 200);
PAINT MONO (4250 200);
DISPLAY INVISIBLE (4250 200);
FORCEPROP 2 LAST PAGE_BORDER TRUE
J 0
(-3640 5450);
DISPLAY 0.638298 (-3640 5450);
PAINT PINK (-3640 5450);
DISPLAY INVISIBLE (-3640 5450);
FORCEPROP 1 LAST CDS_CON_LAST_MODIFIED Tue Dec 01 11:48:56 2015
J 0
(2825 525);
PAINT ORANGE (2825 525);
DISPLAY INVISIBLE (2825 525);
FORCEPROP 2 LAST CDS_XR_PAGE_TITLE CR-180 : @BASEBOARD_FAB2_LIB.BASEBOARD_FAB2(SCH_1):PAGE180
J 0
(-3640 5450);
DISPLAY 0.638298 (-3640 5450);
PAINT PINK (-3640 5450);
DISPLAY INVISIBLE (-3640 5450);
QUIT
